(kicad_pcb
	(version 20260206)
	(generator "pcbnew")
	(generator_version "10.0")
	(general
		(thickness 1.6)
		(legacy_teardrops no)
	)
	(paper "A4")
	(title_block
		(title "03242023_DA0F0TMBIJ0_F0T_Motherboard_J_brd_V01_OCP.brd")
		(comment 1 "Grand Teton / footprints 1659-1659 of 6105")
	)
	(layers
		(0 "F.Cu" signal "TOP")
		(4 "In1.Cu" signal "GND")
		(6 "In2.Cu" signal "IN1")
		(8 "In3.Cu" signal "GND1")
		(10 "In4.Cu" signal "IN2")
		(12 "In5.Cu" signal "GND2")
		(14 "In6.Cu" signal "IN3")
		(16 "In7.Cu" signal "GND3")
		(18 "In8.Cu" signal "VCC")
		(20 "In9.Cu" signal "VCC1")
		(22 "In10.Cu" signal "GND4")
		(24 "In11.Cu" signal "IN4")
		(26 "In12.Cu" signal "GND5")
		(28 "In13.Cu" signal "IN5")
		(30 "In14.Cu" signal "GND6")
		(32 "In15.Cu" signal "IN6")
		(34 "In16.Cu" signal "GND7")
		(2 "B.Cu" signal "BOTTOM")
		(9 "F.Adhes" user "F.Adhesive")
		(11 "B.Adhes" user "B.Adhesive")
		(13 "F.Paste" user "Package Geometry/Pastemask Top")
		(15 "B.Paste" user "Package Geometry/Pastemask Bottom")
		(5 "F.SilkS" user "Ref Des/Silkscreen Top")
		(7 "B.SilkS" user "Ref Des/Silkscreen Bottom")
		(1 "F.Mask" user "Board Geometry/Soldermask Top")
		(3 "B.Mask" user "Board Geometry/Soldermask Bottom")
		(17 "Dwgs.User" user "User.Drawings")
		(19 "Cmts.User" user "User.Comments")
		(21 "Eco1.User" user "User.Eco1")
		(23 "Eco2.User" user "User.Eco2")
		(25 "Edge.Cuts" user "Board Geometry/Outline")
		(27 "Margin" user)
		(31 "F.CrtYd" user "Package Geometry/Place Bound Top")
		(29 "B.CrtYd" user "Package Geometry/Place Bound Bottom")
		(35 "F.Fab" user "Ref Des/Assembly Top")
		(33 "B.Fab" user "Ref Des/Assembly Bottom")
	)
	(footprint ""
		(layer "F.Cu")
		(at 364.50143 -256.654046 -90)
		(property "Reference" "C984"
			(at 0 0 270)
			(layer "F.SilkS")
			(hide yes)
			(effects
				(font
					(size 1.27 1.27)
				)
			)
		)
		(property "Value" ""
			(at 0 0 270)
			(layer "F.Fab")
			(effects
				(font
					(size 1.27 1.27)
				)
			)
		)
		(duplicate_pad_numbers_are_jumpers no)
		(fp_line
			(start -0.7874 0.4064)
			(end -0.7874 -0.4064)
			(stroke
				(width 0.1524)
				(type default)
			)
			(layer "F.SilkS")
		)
		(fp_line
			(start 0.7874 0.4064)
			(end -0.7874 0.4064)
			(stroke
				(width 0.1524)
				(type default)
			)
			(layer "F.SilkS")
		)
		(fp_line
			(start -0.7874 -0.4064)
			(end 0.7874 -0.4064)
			(stroke
				(width 0.1524)
				(type default)
			)
			(layer "F.SilkS")
		)
		(fp_line
			(start 0.7874 -0.4064)
			(end 0.7874 0.4064)
			(stroke
				(width 0.1524)
				(type default)
			)
			(layer "F.SilkS")
		)
		(fp_line
			(start -0.67945 0.3048)
			(end -0.67945 -0.305054)
			(stroke
				(width 0.1)
				(type default)
			)
			(layer "F.Fab")
		)
		(fp_line
			(start -0.12065 0.3048)
			(end -0.67945 0.3048)
			(stroke
				(width 0.1)
				(type default)
			)
			(layer "F.Fab")
		)
		(fp_line
			(start 0.120396 0.3048)
			(end 0.120396 0.2794)
			(stroke
				(width 0.1)
				(type default)
			)
			(layer "F.Fab")
		)
		(fp_line
			(start 0.67945 0.3048)
			(end 0.120396 0.3048)
			(stroke
				(width 0.1)
				(type default)
			)
			(layer "F.Fab")
		)
		(fp_line
			(start -0.12065 0.2794)
			(end -0.12065 0.3048)
			(stroke
				(width 0.1)
				(type default)
			)
			(layer "F.Fab")
		)
		(fp_line
			(start 0.120396 0.2794)
			(end -0.12065 0.2794)
			(stroke
				(width 0.1)
				(type default)
			)
			(layer "F.Fab")
		)
		(fp_line
			(start -0.12065 -0.2794)
			(end 0.12065 -0.2794)
			(stroke
				(width 0.1)
				(type default)
			)
			(layer "F.Fab")
		)
		(fp_line
			(start 0.12065 -0.2794)
			(end 0.12065 -0.3048)
			(stroke
				(width 0.1)
				(type default)
			)
			(layer "F.Fab")
		)
		(fp_line
			(start 0.12065 -0.3048)
			(end 0.67945 -0.3048)
			(stroke
				(width 0.1)
				(type default)
			)
			(layer "F.Fab")
		)
		(fp_line
			(start 0.67945 -0.3048)
			(end 0.67945 0.3048)
			(stroke
				(width 0.1)
				(type default)
			)
			(layer "F.Fab")
		)
		(fp_line
			(start -0.67945 -0.305054)
			(end -0.12065 -0.305054)
			(stroke
				(width 0.1)
				(type default)
			)
			(layer "F.Fab")
		)
		(fp_line
			(start -0.12065 -0.305054)
			(end -0.12065 -0.2794)
			(stroke
				(width 0.1)
				(type default)
			)
			(layer "F.Fab")
		)
		(pad "1" smd circle
			(at -0.40005 0 270)
			(size 0 0)
			(layers "F.Cu" "F.Mask" "F.Paste")
			(net "PVCCIN_CPU0")
		)
		(pad "2" smd circle
			(at 0.40005 0 270)
			(size 0 0)
			(layers "F.Cu" "F.Mask" "F.Paste")
			(net "GND")
		)
	)
)
